# T6G (Grand Teton) — schematic netlist excerpt (pin names and nets, part order shuffled) for the footprints in the layout excerpt that follows; sources: Cadence DE-HDL packaged netlist, KiCad conversion of 04192023_DAF0TMB3IC0_F0TG_MB_C_brd_V02_OCP.brd

C918  Q_CAP_DIFFBUS  DIFF BUS_0.22UF 6.3V 20% X6S  pkg C0201  page 63 : \1\ = P5E_CPU0_P0_TX_C_DN<7> ; \2\ = P5E_CPU0_P0_TX_DN<7>
R2660  Q_RES  0 5% CHIP  pkg 0402LF  page 28 : A = CLK_100M_CPU0_CLK11_R_DN ; B = CLK_100M_CPU0_CLK11_DN
D6  Q_LED  IC  pkg SMLF  page 166 : A = PU_SMERR_LED ; C = SMERR_LED_N

(kicad_pcb
	(version 20260206)
	(generator "pcbnew")
	(generator_version "10.0")
	(general
		(thickness 1.6)
		(legacy_teardrops no)
	)
	(paper "A4")
	(title_block
		(title "04192023_DAF0TMB3IC0_F0TG_MB_C_brd_V02_OCP.brd")
		(comment 1 "Grand Teton / footprints 1297-1299 of 8354")
	)
	(layers
		(0 "F.Cu" signal "TOP")
		(4 "In1.Cu" signal "GND")
		(6 "In2.Cu" signal "IN1")
		(8 "In3.Cu" signal "GND1")
		(10 "In4.Cu" signal "IN2")
		(12 "In5.Cu" signal "GND2")
		(14 "In6.Cu" signal "IN3")
		(16 "In7.Cu" signal "GND3")
		(18 "In8.Cu" signal "VCC")
		(20 "In9.Cu" signal "VCC1")
		(22 "In10.Cu" signal "GND4")
		(24 "In11.Cu" signal "IN4")
		(26 "In12.Cu" signal "GND5")
		(28 "In13.Cu" signal "IN5")
		(30 "In14.Cu" signal "GND6")
		(32 "In15.Cu" signal "IN6")
		(34 "In16.Cu" signal "GND7")
		(2 "B.Cu" signal "BOTTOM")
		(9 "F.Adhes" user "F.Adhesive")
		(11 "B.Adhes" user "B.Adhesive")
		(13 "F.Paste" user "Package Geometry/Pastemask Top")
		(15 "B.Paste" user "Package Geometry/Pastemask Bottom")
		(5 "F.SilkS" user "Ref Des/Silkscreen Top")
		(7 "B.SilkS" user "Ref Des/Silkscreen Bottom")
		(1 "F.Mask" user "Board Geometry/Soldermask Top")
		(3 "B.Mask" user "Board Geometry/Soldermask Bottom")
		(17 "Dwgs.User" user "User.Drawings")
		(19 "Cmts.User" user "User.Comments")
		(21 "Eco1.User" user "User.Eco1")
		(23 "Eco2.User" user "User.Eco2")
		(25 "Edge.Cuts" user "Board Geometry/Outline")
		(27 "Margin" user)
		(31 "F.CrtYd" user "Package Geometry/Place Bound Top")
		(29 "B.CrtYd" user "Package Geometry/Place Bound Bottom")
		(35 "F.Fab" user "Ref Des/Assembly Top")
		(33 "B.Fab" user "Ref Des/Assembly Bottom")
	)
	(footprint ""
		(layer "F.Cu")
		(at 365.387128 -324.29704 90)
		(property "Reference" "R2660"
			(at 0 0 90)
			(layer "F.SilkS")
			(hide yes)
			(effects
				(font
					(size 1.27 1.27)
				)
			)
		)
		(property "Value" ""
			(at 0 0 90)
			(layer "F.Fab")
			(effects
				(font
					(size 1.27 1.27)
				)
			)
		)
		(duplicate_pad_numbers_are_jumpers no)
		(fp_line
			(start 0.7874 -0.4064)
			(end 0.7874 -0.008128)
			(stroke
				(width 0.1524)
				(type default)
			)
			(layer "F.SilkS")
		)
		(fp_line
			(start -0.7874 -0.4064)
			(end 0.7874 -0.4064)
			(stroke
				(width 0.1524)
				(type default)
			)
			(layer "F.SilkS")
		)
		(fp_line
			(start -0.7874 -0.008128)
			(end -0.7874 -0.4064)
			(stroke
				(width 0.1524)
				(type default)
			)
			(layer "F.SilkS")
		)
		(fp_line
			(start 0.39116 0.4064)
			(end -0.34544 0.4064)
			(stroke
				(width 0.1524)
				(type default)
			)
			(layer "F.SilkS")
		)
		(fp_line
			(start -0.12065 -0.305054)
			(end -0.12065 -0.2794)
			(stroke
				(width 0.1)
				(type default)
			)
			(layer "F.Fab")
		)
		(fp_line
			(start -0.67945 -0.305054)
			(end -0.12065 -0.305054)
			(stroke
				(width 0.1)
				(type default)
			)
			(layer "F.Fab")
		)
		(fp_line
			(start 0.67945 -0.3048)
			(end 0.67945 0.3048)
			(stroke
				(width 0.1)
				(type default)
			)
			(layer "F.Fab")
		)
		(fp_line
			(start 0.12065 -0.3048)
			(end 0.67945 -0.3048)
			(stroke
				(width 0.1)
				(type default)
			)
			(layer "F.Fab")
		)
		(fp_line
			(start 0.12065 -0.2794)
			(end 0.12065 -0.3048)
			(stroke
				(width 0.1)
				(type default)
			)
			(layer "F.Fab")
		)
		(fp_line
			(start -0.12065 -0.2794)
			(end 0.12065 -0.2794)
			(stroke
				(width 0.1)
				(type default)
			)
			(layer "F.Fab")
		)
		(fp_line
			(start 0.120396 0.2794)
			(end -0.12065 0.2794)
			(stroke
				(width 0.1)
				(type default)
			)
			(layer "F.Fab")
		)
		(fp_line
			(start -0.12065 0.2794)
			(end -0.12065 0.3048)
			(stroke
				(width 0.1)
				(type default)
			)
			(layer "F.Fab")
		)
		(fp_line
			(start 0.67945 0.3048)
			(end 0.120396 0.3048)
			(stroke
				(width 0.1)
				(type default)
			)
			(layer "F.Fab")
		)
		(fp_line
			(start 0.120396 0.3048)
			(end 0.120396 0.2794)
			(stroke
				(width 0.1)
				(type default)
			)
			(layer "F.Fab")
		)
		(fp_line
			(start -0.12065 0.3048)
			(end -0.67945 0.3048)
			(stroke
				(width 0.1)
				(type default)
			)
			(layer "F.Fab")
		)
		(fp_line
			(start -0.67945 0.3048)
			(end -0.67945 -0.305054)
			(stroke
				(width 0.1)
				(type default)
			)
			(layer "F.Fab")
		)
		(pad "1" smd circle
			(at -0.40005 0 90)
			(size 0 0)
			(layers "F.Cu" "F.Mask" "F.Paste")
			(net "CLK_100M_CPU0_CLK11_R_DN")
		)
		(pad "2" smd circle
			(at 0.40005 0 90)
			(size 0 0)
			(layers "F.Cu" "F.Mask" "F.Paste")
			(net "CLK_100M_CPU0_CLK11_DN")
		)
	)
	(footprint ""
		(layer "F.Cu")
		(at 342.7349 -16.178276 90)
		(property "Reference" "D6"
			(at -3.95732 -1.496568 90)
			(unlocked yes)
			(layer "F.SilkS")
			(effects
				(font
					(size 0.7874 0.5842)
					(thickness 0.1524)
				)
				(justify left)
			)
		)
		(property "Value" ""
			(at 0 0 90)
			(layer "F.Fab")
			(effects
				(font
					(size 1.27 1.27)
				)
			)
		)
		(duplicate_pad_numbers_are_jumpers no)
		(fp_line
			(start 1.778 -0.5588)
			(end 1.3208 -0.5588)
			(stroke
				(width 0.1524)
				(type default)
			)
			(layer "F.SilkS")
		)
		(fp_line
			(start 1.778 -0.5588)
			(end 1.778 0.5588)
			(stroke
				(width 0.1524)
				(type default)
			)
			(layer "F.SilkS")
		)
		(fp_line
			(start 1.4732 -0.5588)
			(end 1.4732 0.5588)
			(stroke
				(width 0.1524)
				(type default)
			)
			(layer "F.SilkS")
		)
		(fp_line
			(start 1.3208 -0.5588)
			(end 1.3208 0.5588)
			(stroke
				(width 0.1524)
				(type default)
			)
			(layer "F.SilkS")
		)
		(fp_line
			(start -1.3208 -0.5588)
			(end 1.3208 -0.5588)
			(stroke
				(width 0.1524)
				(type default)
			)
			(layer "F.SilkS")
		)
		(fp_line
			(start 1.778 0.5588)
			(end 1.3208 0.5588)
			(stroke
				(width 0.1524)
				(type default)
			)
			(layer "F.SilkS")
		)
		(fp_line
			(start 1.6256 0.5588)
			(end 1.6256 -0.5588)
			(stroke
				(width 0.1524)
				(type default)
			)
			(layer "F.SilkS")
		)
		(fp_line
			(start 1.3208 0.5588)
			(end -1.3208 0.5588)
			(stroke
				(width 0.1524)
				(type default)
			)
			(layer "F.SilkS")
		)
		(fp_line
			(start -1.3208 0.5588)
			(end -1.3208 -0.5588)
			(stroke
				(width 0.1524)
				(type default)
			)
			(layer "F.SilkS")
		)
		(fp_line
			(start 0.899922 -0.40005)
			(end 0.899922 0.40005)
			(stroke
				(width 0.1)
				(type default)
			)
			(layer "F.Fab")
		)
		(fp_line
			(start -0.899922 -0.40005)
			(end 0.899922 -0.40005)
			(stroke
				(width 0.1)
				(type default)
			)
			(layer "F.Fab")
		)
		(fp_line
			(start 0.899922 0.40005)
			(end -0.899922 0.40005)
			(stroke
				(width 0.1)
				(type default)
			)
			(layer "F.Fab")
		)
		(fp_line
			(start -0.899922 0.40005)
			(end -0.899922 -0.40005)
			(stroke
				(width 0.1)
				(type default)
			)
			(layer "F.Fab")
		)
		(fp_text user "+"
			(at -2.620518 -0.653796 90)
			(unlocked yes)
			(layer "F.SilkS")
			(effects
				(font
					(size 1.905 1.4224)
					(thickness 0.1524)
				)
				(justify left)
			)
		)
		(fp_text user "-"
			(at 1.651 -0.22225 90)
			(unlocked yes)
			(layer "F.SilkS")
			(effects
				(font
					(size 1.905 1.4224)
					(thickness 0.1524)
				)
				(justify left)
			)
		)
		(fp_text user "-"
			(at 1.651 -0.22225 90)
			(unlocked yes)
			(layer "F.Fab")
			(effects
				(font
					(size 1.905 1.4224)
					(thickness 0.1524)
				)
				(justify left)
			)
		)
		(fp_text user "+"
			(at -2.6162 -0.22225 90)
			(unlocked yes)
			(layer "F.Fab")
			(effects
				(font
					(size 1.905 1.4224)
					(thickness 0.1524)
				)
				(justify left)
			)
		)
		(pad "A" smd rect
			(at -0.750062 0 90)
			(size 0.8128 0.8128)
			(layers "F.Cu" "F.Mask" "F.Paste")
			(net "PU_SMERR_LED")
		)
		(pad "C" smd rect
			(at 0.750062 0 90)
			(size 0.8128 0.8128)
			(layers "F.Cu" "F.Mask" "F.Paste")
			(net "SMERR_LED_N")
		)
	)
	(footprint ""
		(layer "F.Cu")
		(at 311.816496 -383.88163 -90)
		(property "Reference" "C918"
			(at 0 0 270)
			(layer "F.SilkS")
			(hide yes)
			(effects
				(font
					(size 1.27 1.27)
				)
			)
		)
		(property "Value" ""
			(at 0 0 270)
			(layer "F.Fab")
			(effects
				(font
					(size 1.27 1.27)
				)
			)
		)
		(duplicate_pad_numbers_are_jumpers no)
		(fp_line
			(start -0.299974 0.150114)
			(end -0.299974 -0.150114)
			(stroke
				(width 0.1)
				(type default)
			)
			(layer "F.Fab")
		)
		(fp_line
			(start 0.299974 0.150114)
			(end -0.299974 0.150114)
			(stroke
				(width 0.1)
				(type default)
			)
			(layer "F.Fab")
		)
		(fp_line
			(start -0.299974 -0.150114)
			(end 0.299974 -0.150114)
			(stroke
				(width 0.1)
				(type default)
			)
			(layer "F.Fab")
		)
		(fp_line
			(start 0.299974 -0.150114)
			(end 0.299974 0.150114)
			(stroke
				(width 0.1)
				(type default)
			)
			(layer "F.Fab")
		)
		(pad "1" smd rect
			(at -0.2667 0 270)
			(size 0.3048 0.381)
			(layers "F.Cu" "F.Mask" "F.Paste")
			(net "P5E_CPU0_P0_TX_C_DN<7>")
		)
		(pad "2" smd rect
			(at 0.2667 0 270)
			(size 0.3048 0.381)
			(layers "F.Cu" "F.Mask" "F.Paste")
			(net "P5E_CPU0_P0_TX_DN<7>")
		)
	)
)
